# BASEBOARD_FAB2 (Tioga Pass) — schematic netlist excerpt (pin names and nets, part order shuffled) for the footprints in the layout excerpt that follows; sources: Cadence DE-HDL packaged netlist, KiCad conversion of Wiwynn_Tioga_Pass_MB.brd

R3R12  RES  665 1.0% CHIP  pkg 0402  page 99 : A = PVPP_DEF ; B = SMB_DDR_DEF_VPP_SDA_R
R3N23  RES  2.26K 1.0% EMPTY  pkg 0402  page 211 : A = P3V3_STBY ; B = PU_VR_PVCCIO_CPU0_FAULT1
R7C21  RES  10.0K 1% CHIP  pkg 0402  page 134 : A = P1V05_PCH_STBY ; B = FM_PCH_LVC1_THERMTRIP_N

(kicad_pcb
	(version 20260206)
	(generator "pcbnew")
	(generator_version "10.0")
	(general
		(thickness 1.6)
		(legacy_teardrops no)
	)
	(paper "A4")
	(title_block
		(title "Wiwynn_Tioga_Pass_MB.brd")
		(comment 1 "Tioga Pass / footprints 3086-3088 of 4770")
	)
	(layers
		(0 "F.Cu" signal "TOP")
		(4 "In1.Cu" signal "L2GND")
		(6 "In2.Cu" signal "L3")
		(8 "In3.Cu" signal "L4GND")
		(10 "In4.Cu" signal "L5")
		(12 "In5.Cu" signal "L6GND")
		(14 "In6.Cu" signal "L7VCC")
		(16 "In7.Cu" signal "L8VCC")
		(18 "In8.Cu" signal "L9GND")
		(20 "In9.Cu" signal "L10")
		(22 "In10.Cu" signal "L11GND")
		(24 "In11.Cu" signal "L12")
		(26 "In12.Cu" signal "L13GND")
		(2 "B.Cu" signal "BOTTOM")
		(9 "F.Adhes" user "F.Adhesive")
		(11 "B.Adhes" user "B.Adhesive")
		(13 "F.Paste" user "Package Geometry/Pastemask Top")
		(15 "B.Paste" user "Package Geometry/Pastemask Bottom")
		(5 "F.SilkS" user "Ref Des/Silkscreen Top")
		(7 "B.SilkS" user "Ref Des/Silkscreen Bottom")
		(1 "F.Mask" user "Board Geometry/Soldermask Top")
		(3 "B.Mask" user "Board Geometry/Soldermask Bottom")
		(17 "Dwgs.User" user "User.Drawings")
		(19 "Cmts.User" user "User.Comments")
		(21 "Eco1.User" user "User.Eco1")
		(23 "Eco2.User" user "User.Eco2")
		(25 "Edge.Cuts" user "Board Geometry/Outline")
		(27 "Margin" user)
		(31 "F.CrtYd" user "Package Geometry/Place Bound Top")
		(29 "B.CrtYd" user "Package Geometry/Place Bound Bottom")
		(35 "F.Fab" user "Ref Des/Assembly Top")
		(33 "B.Fab" user "Ref Des/Assembly Bottom")
	)
	(footprint ""
		(layer "B.Cu")
		(at 376.174 -88.0745)
		(property "Reference" "R7C21"
			(at 0.8382 -0.67818 0)
			(unlocked yes)
			(layer "B.SilkS")
			(effects
				(font
					(size 0.4064 0.254)
					(thickness 0.1524)
				)
				(justify left mirror)
			)
		)
		(property "Value" ""
			(at 0 0 0)
			(layer "B.Fab")
			(effects
				(font
					(size 1.27 1.27)
				)
				(justify mirror)
			)
		)
		(duplicate_pad_numbers_are_jumpers no)
		(fp_poly
			(pts
				(xy 0.2794 -0.1016) (xy -0.2794 -0.1016) (xy -0.2794 0.9906) (xy 0.2794 0.9906)
			)
			(stroke
				(width 0)
				(type default)
			)
			(fill no)
			(layer "B.CrtYd")
		)
		(fp_line
			(start -0.2794 -0.1016)
			(end 0.2794 -0.1016)
			(stroke
				(width 0.1)
				(type default)
			)
			(layer "B.Fab")
		)
		(fp_line
			(start -0.2794 0.9906)
			(end -0.2794 -0.1016)
			(stroke
				(width 0.1)
				(type default)
			)
			(layer "B.Fab")
		)
		(fp_line
			(start 0.2794 -0.1016)
			(end 0.2794 0.9906)
			(stroke
				(width 0.1)
				(type default)
			)
			(layer "B.Fab")
		)
		(fp_line
			(start 0.2794 0.9906)
			(end -0.2794 0.9906)
			(stroke
				(width 0.1)
				(type default)
			)
			(layer "B.Fab")
		)
		(pad "1" smd rect
			(at 0 0 180)
			(size 0.508 0.508)
			(layers "B.Cu" "B.Mask" "B.Paste")
			(net "P1V05_PCH_STBY")
		)
		(pad "2" smd rect
			(at 0 0.889 180)
			(size 0.508 0.508)
			(layers "B.Cu" "B.Mask" "B.Paste")
			(net "FM_PCH_LVC1_THERMTRIP_N")
		)
		(zone
			(layer "B.Cu")
			(hatch none 0.5)
			(connect_pads
				(clearance 0)
			)
			(min_thickness 0.25)
			(keepout
				(tracks allowed)
				(vias not_allowed)
				(pads allowed)
				(copperpour not_allowed)
				(footprints allowed)
			)
			(placement
				(enabled no)
				(sheetname "")
			)
			(fill
				(thermal_gap 0.5)
				(thermal_bridge_width 0.5)
				(island_removal_mode 0)
			)
			(polygon
				(pts
					(xy 376.428 -87.8205) (xy 375.92 -87.8205) (xy 375.92 -87.4395) (xy 376.428 -87.4395)
				)
			)
		)
		(zone
			(layer "B.Cu")
			(hatch none 0.5)
			(connect_pads
				(clearance 0)
			)
			(min_thickness 0.25)
			(keepout
				(tracks not_allowed)
				(vias allowed)
				(pads allowed)
				(copperpour not_allowed)
				(footprints allowed)
			)
			(placement
				(enabled no)
				(sheetname "")
			)
			(fill
				(thermal_gap 0.5)
				(thermal_bridge_width 0.5)
				(island_removal_mode 0)
			)
			(polygon
				(pts
					(xy 376.428 -87.4395) (xy 375.92 -87.4395) (xy 375.92 -87.8205) (xy 376.428 -87.8205)
				)
			)
		)
	)
	(footprint ""
		(layer "B.Cu")
		(at 316.2808 -120.3198 90)
		(property "Reference" "R3R12"
			(at 0 0 90)
			(layer "B.SilkS")
			(hide yes)
			(effects
				(font
					(size 1.27 1.27)
				)
				(justify mirror)
			)
		)
		(property "Value" ""
			(at 0 0 90)
			(layer "B.Fab")
			(effects
				(font
					(size 1.27 1.27)
				)
				(justify mirror)
			)
		)
		(duplicate_pad_numbers_are_jumpers no)
		(fp_poly
			(pts
				(xy 0.2794 -0.1016) (xy -0.2794 -0.1016) (xy -0.2794 0.9906) (xy 0.2794 0.9906)
			)
			(stroke
				(width 0)
				(type default)
			)
			(fill no)
			(layer "B.CrtYd")
		)
		(fp_line
			(start 0.2794 -0.1016)
			(end 0.2794 0.9906)
			(stroke
				(width 0.1)
				(type default)
			)
			(layer "B.Fab")
		)
		(fp_line
			(start -0.2794 -0.1016)
			(end 0.2794 -0.1016)
			(stroke
				(width 0.1)
				(type default)
			)
			(layer "B.Fab")
		)
		(fp_line
			(start 0.2794 0.9906)
			(end -0.2794 0.9906)
			(stroke
				(width 0.1)
				(type default)
			)
			(layer "B.Fab")
		)
		(fp_line
			(start -0.2794 0.9906)
			(end -0.2794 -0.1016)
			(stroke
				(width 0.1)
				(type default)
			)
			(layer "B.Fab")
		)
		(pad "1" smd rect
			(at 0 0 270)
			(size 0.508 0.508)
			(layers "B.Cu" "B.Mask" "B.Paste")
			(net "PVPP_DEF")
		)
		(pad "2" smd rect
			(at 0 0.889 270)
			(size 0.508 0.508)
			(layers "B.Cu" "B.Mask" "B.Paste")
			(net "SMB_DDR_DEF_VPP_SDA_R")
		)
		(zone
			(layer "B.Cu")
			(hatch none 0.5)
			(connect_pads
				(clearance 0)
			)
			(min_thickness 0.25)
			(keepout
				(tracks allowed)
				(vias not_allowed)
				(pads allowed)
				(copperpour not_allowed)
				(footprints allowed)
			)
			(placement
				(enabled no)
				(sheetname "")
			)
			(fill
				(thermal_gap 0.5)
				(thermal_bridge_width 0.5)
				(island_removal_mode 0)
			)
			(polygon
				(pts
					(xy 316.5348 -120.5738) (xy 316.5348 -120.0658) (xy 316.9158 -120.0658) (xy 316.9158 -120.5738)
				)
			)
		)
		(zone
			(layer "B.Cu")
			(hatch none 0.5)
			(connect_pads
				(clearance 0)
			)
			(min_thickness 0.25)
			(keepout
				(tracks not_allowed)
				(vias allowed)
				(pads allowed)
				(copperpour not_allowed)
				(footprints allowed)
			)
			(placement
				(enabled no)
				(sheetname "")
			)
			(fill
				(thermal_gap 0.5)
				(thermal_bridge_width 0.5)
				(island_removal_mode 0)
			)
			(polygon
				(pts
					(xy 316.9158 -120.5738) (xy 316.9158 -120.0658) (xy 316.5348 -120.0658) (xy 316.5348 -120.5738)
				)
			)
		)
	)
	(footprint ""
		(layer "B.Cu")
		(at 351.86112 -90.639392 -90)
		(property "Reference" "R3N23"
			(at 0 0 90)
			(layer "B.SilkS")
			(hide yes)
			(effects
				(font
					(size 1.27 1.27)
				)
				(justify mirror)
			)
		)
		(property "Value" ""
			(at 0 0 90)
			(layer "B.Fab")
			(effects
				(font
					(size 1.27 1.27)
				)
				(justify mirror)
			)
		)
		(duplicate_pad_numbers_are_jumpers no)
		(fp_poly
			(pts
				(xy 0.2794 -0.1016) (xy -0.2794 -0.1016) (xy -0.2794 0.9906) (xy 0.2794 0.9906)
			)
			(stroke
				(width 0)
				(type default)
			)
			(fill no)
			(layer "B.CrtYd")
		)
		(fp_line
			(start -0.2794 0.9906)
			(end -0.2794 -0.1016)
			(stroke
				(width 0.1)
				(type default)
			)
			(layer "B.Fab")
		)
		(fp_line
			(start 0.2794 0.9906)
			(end -0.2794 0.9906)
			(stroke
				(width 0.1)
				(type default)
			)
			(layer "B.Fab")
		)
		(fp_line
			(start -0.2794 -0.1016)
			(end 0.2794 -0.1016)
			(stroke
				(width 0.1)
				(type default)
			)
			(layer "B.Fab")
		)
		(fp_line
			(start 0.2794 -0.1016)
			(end 0.2794 0.9906)
			(stroke
				(width 0.1)
				(type default)
			)
			(layer "B.Fab")
		)
		(pad "1" smd rect
			(at 0 0 90)
			(size 0.508 0.508)
			(layers "B.Cu" "B.Mask" "B.Paste")
			(net "P3V3_STBY")
		)
		(pad "2" smd rect
			(at 0 0.889 90)
			(size 0.508 0.508)
			(layers "B.Cu" "B.Mask" "B.Paste")
			(net "PU_VR_PVCCIO_CPU0_FAULT1")
		)
		(zone
			(layer "B.Cu")
			(hatch none 0.5)
			(connect_pads
				(clearance 0)
			)
			(min_thickness 0.25)
			(keepout
				(tracks not_allowed)
				(vias allowed)
				(pads allowed)
				(copperpour not_allowed)
				(footprints allowed)
			)
			(placement
				(enabled no)
				(sheetname "")
			)
			(fill
				(thermal_gap 0.5)
				(thermal_bridge_width 0.5)
				(island_removal_mode 0)
			)
			(polygon
				(pts
					(xy 351.22612 -90.385392) (xy 351.22612 -90.893392) (xy 351.60712 -90.893392) (xy 351.60712 -90.385392)
				)
			)
		)
		(zone
			(layer "B.Cu")
			(hatch none 0.5)
			(connect_pads
				(clearance 0)
			)
			(min_thickness 0.25)
			(keepout
				(tracks allowed)
				(vias not_allowed)
				(pads allowed)
				(copperpour not_allowed)
				(footprints allowed)
			)
			(placement
				(enabled no)
				(sheetname "")
			)
			(fill
				(thermal_gap 0.5)
				(thermal_bridge_width 0.5)
				(island_removal_mode 0)
			)
			(polygon
				(pts
					(xy 351.60712 -90.385392) (xy 351.60712 -90.893392) (xy 351.22612 -90.893392) (xy 351.22612 -90.385392)
				)
			)
		)
	)
)
